(kicad_pcb
	(version 20260206)
	(generator "pcbnew")
	(generator_version "10.0")
	(general
		(thickness 1.6)
		(legacy_teardrops no)
	)
	(paper "A4")
	(title_block
		(title "04192023_DAF0TMB3IC0_F0TG_MB_C_brd_V02_OCP.brd")
		(comment 1 "Grand Teton / footprint 3955 of 8354 (U25), pads 4784-4896 of 6102")
	)
	(layers
		(0 "F.Cu" signal "TOP")
		(4 "In1.Cu" signal "GND")
		(6 "In2.Cu" signal "IN1")
		(8 "In3.Cu" signal "GND1")
		(10 "In4.Cu" signal "IN2")
		(12 "In5.Cu" signal "GND2")
		(14 "In6.Cu" signal "IN3")
		(16 "In7.Cu" signal "GND3")
		(18 "In8.Cu" signal "VCC")
		(20 "In9.Cu" signal "VCC1")
		(22 "In10.Cu" signal "GND4")
		(24 "In11.Cu" signal "IN4")
		(26 "In12.Cu" signal "GND5")
		(28 "In13.Cu" signal "IN5")
		(30 "In14.Cu" signal "GND6")
		(32 "In15.Cu" signal "IN6")
		(34 "In16.Cu" signal "GND7")
		(2 "B.Cu" signal "BOTTOM")
		(9 "F.Adhes" user "F.Adhesive")
		(11 "B.Adhes" user "B.Adhesive")
		(13 "F.Paste" user "Package Geometry/Pastemask Top")
		(15 "B.Paste" user "Package Geometry/Pastemask Bottom")
		(5 "F.SilkS" user "Ref Des/Silkscreen Top")
		(7 "B.SilkS" user "Ref Des/Silkscreen Bottom")
		(1 "F.Mask" user "Board Geometry/Soldermask Top")
		(3 "B.Mask" user "Board Geometry/Soldermask Bottom")
		(17 "Dwgs.User" user "User.Drawings")
		(19 "Cmts.User" user "User.Comments")
		(21 "Eco1.User" user "User.Eco1")
		(23 "Eco2.User" user "User.Eco2")
		(25 "Edge.Cuts" user "Board Geometry/Outline")
		(27 "Margin" user)
		(31 "F.CrtYd" user "Package Geometry/Place Bound Top")
		(29 "B.CrtYd" user "Package Geometry/Place Bound Bottom")
		(35 "F.Fab" user "Ref Des/Assembly Top")
		(33 "B.Fab" user "Ref Des/Assembly Bottom")
	)
	(footprint ""
		(layer "F.Cu")
		(at 359.867962 -258.880102 180)
		(property "Reference" "U25"
			(at -45.78477 -62.086744 0)
			(unlocked yes)
			(layer "F.SilkS")
			(effects
				(font
					(size 0.7874 0.5842)
					(thickness 0.1524)
				)
			)
		)
		(property "Value" ""
			(at 0 0 180)
			(layer "F.Fab")
			(effects
				(font
					(size 1.27 1.27)
				)
			)
		)
		(duplicate_pad_numbers_are_jumpers no)
		(pad "DG32" smd circle
			(at -5.32003 35.189922 180)
			(size 0.450088 0.450088)
			(layers "F.Cu" "F.Mask" "F.Paste")
			(net "CPU0_ROM_TYPE_SELECT")
		)
		(pad "DG33" smd circle
			(at -4.379976 35.189922 180)
			(size 0.450088 0.450088)
			(layers "F.Cu" "F.Mask" "F.Paste")
			(net "GND")
		)
		(pad "DG34" smd circle
			(at -3.439922 35.189922 180)
			(size 0.450088 0.450088)
			(layers "F.Cu" "F.Mask" "F.Paste")
			(net "TP_CPU0_UART0_INTR")
		)
		(pad "DG35" smd circle
			(at -2.500122 35.189922 180)
			(size 0.450088 0.450088)
			(layers "F.Cu" "F.Mask" "F.Paste")
			(net "UART_CPU0_UART0_RX")
		)
		(pad "DG36" smd circle
			(at -1.560068 35.189922 180)
			(size 0.450088 0.450088)
			(layers "F.Cu" "F.Mask" "F.Paste")
			(net "RST_CPU0_PERST1_N")
		)
		(pad "DG40" smd circle
			(at 1.260094 35.189922 180)
			(size 0.450088 0.450088)
			(layers "F.Cu" "F.Mask" "F.Paste")
			(net "Net_1888")
		)
		(pad "DG41" smd circle
			(at 2.199894 35.189922 180)
			(size 0.450088 0.450088)
			(layers "F.Cu" "F.Mask" "F.Paste")
			(net "GND")
		)
		(pad "DG42" smd circle
			(at 3.139948 35.189922 180)
			(size 0.450088 0.450088)
			(layers "F.Cu" "F.Mask" "F.Paste")
			(net "Net_1952")
		)
		(pad "DG43" smd circle
			(at 4.080002 35.189922 180)
			(size 0.450088 0.450088)
			(layers "F.Cu" "F.Mask" "F.Paste")
			(net "GND")
		)
		(pad "DG44" smd circle
			(at 5.020056 35.189922 180)
			(size 0.450088 0.450088)
			(layers "F.Cu" "F.Mask" "F.Paste")
			(net "P3E_CPU0_P4_RX_DN<3>")
		)
		(pad "DG45" smd circle
			(at 5.96011 35.189922 180)
			(size 0.450088 0.450088)
			(layers "F.Cu" "F.Mask" "F.Paste")
			(net "P3E_CPU0_P4_RX_DP<3>")
		)
		(pad "DG46" smd circle
			(at 6.89991 35.189922 180)
			(size 0.450088 0.450088)
			(layers "F.Cu" "F.Mask" "F.Paste")
			(net "GND")
		)
		(pad "DG47" smd circle
			(at 7.839964 35.189922 180)
			(size 0.450088 0.450088)
			(layers "F.Cu" "F.Mask" "F.Paste")
			(net "P3E_CPU0_P4_RX_DN<2>")
		)
		(pad "DG48" smd circle
			(at 8.780018 35.189922 180)
			(size 0.450088 0.450088)
			(layers "F.Cu" "F.Mask" "F.Paste")
			(net "P3E_CPU0_P4_RX_DP<2>")
		)
		(pad "DG49" smd circle
			(at 9.720072 35.189922 180)
			(size 0.450088 0.450088)
			(layers "F.Cu" "F.Mask" "F.Paste")
			(net "GND")
		)
		(pad "DG50" smd circle
			(at 10.659872 35.189922 180)
			(size 0.450088 0.450088)
			(layers "F.Cu" "F.Mask" "F.Paste")
			(net "P3E_CPU0_P4_RX_DN<1>")
		)
		(pad "DG51" smd circle
			(at 11.599926 35.189922 180)
			(size 0.450088 0.450088)
			(layers "F.Cu" "F.Mask" "F.Paste")
			(net "P3E_CPU0_P4_RX_DP<1>")
		)
		(pad "DG52" smd circle
			(at 12.53998 35.189922 180)
			(size 0.450088 0.450088)
			(layers "F.Cu" "F.Mask" "F.Paste")
			(net "GND")
		)
		(pad "DG53" smd circle
			(at 13.480034 35.189922 180)
			(size 0.450088 0.450088)
			(layers "F.Cu" "F.Mask" "F.Paste")
			(net "P3E_CPU0_P4_RX_DN<0>")
		)
		(pad "DG54" smd circle
			(at 14.420088 35.189922 180)
			(size 0.450088 0.450088)
			(layers "F.Cu" "F.Mask" "F.Paste")
			(net "P3E_CPU0_P4_RX_DP<0>")
		)
		(pad "DG55" smd circle
			(at 15.359888 35.189922 180)
			(size 0.450088 0.450088)
			(layers "F.Cu" "F.Mask" "F.Paste")
			(net "GND")
		)
		(pad "DG56" smd circle
			(at 16.299942 35.189922 180)
			(size 0.450088 0.450088)
			(layers "F.Cu" "F.Mask" "F.Paste")
			(net "GND")
		)
		(pad "DG57" smd circle
			(at 17.239996 35.189922 180)
			(size 0.450088 0.450088)
			(layers "F.Cu" "F.Mask" "F.Paste")
			(net "PVDDCR_CPU1_P0")
		)
		(pad "DG58" smd circle
			(at 18.18005 35.189922 180)
			(size 0.450088 0.450088)
			(layers "F.Cu" "F.Mask" "F.Paste")
			(net "Net_1897")
		)
		(pad "DG59" smd circle
			(at 19.120104 35.189922 180)
			(size 0.450088 0.450088)
			(layers "F.Cu" "F.Mask" "F.Paste")
			(net "GND")
		)
		(pad "DG60" smd circle
			(at 20.059904 35.189922 180)
			(size 0.450088 0.450088)
			(layers "F.Cu" "F.Mask" "F.Paste")
			(net "GND")
		)
		(pad "DG61" smd circle
			(at 20.999958 35.189922 180)
			(size 0.450088 0.450088)
			(layers "F.Cu" "F.Mask" "F.Paste")
			(net "GND")
		)
		(pad "DG62" smd circle
			(at 21.940012 35.189922 180)
			(size 0.450088 0.450088)
			(layers "F.Cu" "F.Mask" "F.Paste")
			(net "GND")
		)
		(pad "DG63" smd circle
			(at 22.880066 35.189922 180)
			(size 0.450088 0.450088)
			(layers "F.Cu" "F.Mask" "F.Paste")
			(net "GND")
		)
		(pad "DG64" smd circle
			(at 23.82012 35.189922 180)
			(size 0.450088 0.450088)
			(layers "F.Cu" "F.Mask" "F.Paste")
			(net "PVDDIO_P0")
		)
		(pad "DG65" smd circle
			(at 24.75992 35.189922 180)
			(size 0.450088 0.450088)
			(layers "F.Cu" "F.Mask" "F.Paste")
			(net "GND")
		)
		(pad "DG66" smd circle
			(at 25.699974 35.189922 180)
			(size 0.450088 0.450088)
			(layers "F.Cu" "F.Mask" "F.Paste")
			(net "GND")
		)
		(pad "DG67" smd circle
			(at 26.640028 35.189922 180)
			(size 0.450088 0.450088)
			(layers "F.Cu" "F.Mask" "F.Paste")
			(net "GND")
		)
		(pad "DG68" smd circle
			(at 27.580082 35.189922 180)
			(size 0.450088 0.450088)
			(layers "F.Cu" "F.Mask" "F.Paste")
			(net "GND")
		)
		(pad "DG69" smd circle
			(at 28.519882 35.189922 180)
			(size 0.450088 0.450088)
			(layers "F.Cu" "F.Mask" "F.Paste")
			(net "GND")
		)
		(pad "DG70" smd circle
			(at 29.459936 35.189922 180)
			(size 0.450088 0.450088)
			(layers "F.Cu" "F.Mask" "F.Paste")
			(net "GND")
		)
		(pad "DG71" smd circle
			(at 30.39999 35.189922 180)
			(size 0.450088 0.450088)
			(layers "F.Cu" "F.Mask" "F.Paste")
			(net "PVDDIO_P0")
		)
		(pad "DG72" smd circle
			(at 31.340044 35.189922 180)
			(size 0.450088 0.450088)
			(layers "F.Cu" "F.Mask" "F.Paste")
			(net "FM_P0_PCC1_N")
		)
		(pad "DG73" smd circle
			(at 32.280098 35.189922 180)
			(size 0.450088 0.450088)
			(layers "F.Cu" "F.Mask" "F.Paste")
			(net "SVID_PVDDCR_CPU1_P0_SVTO")
		)
		(pad "DG74" smd circle
			(at 33.219898 35.189922 180)
			(size 0.450088 0.450088)
			(layers "F.Cu" "F.Mask" "F.Paste")
			(net "GND")
		)
		(pad "DG75" smd circle
			(at 34.159952 35.189922 180)
			(size 0.450088 0.450088)
			(layers "F.Cu" "F.Mask" "F.Paste")
			(net "GND")
		)
		(pad "DH3" smd circle
			(at -33.049972 35.999928 180)
			(size 0.450088 0.450088)
			(layers "F.Cu" "F.Mask" "F.Paste")
			(net "VSENSE_PVDD11_S3_P0_DP")
		)
		(pad "DH4" smd circle
			(at -32.109918 35.999928 180)
			(size 0.450088 0.450088)
			(layers "F.Cu" "F.Mask" "F.Paste")
			(net "FM_BOARD_SKU_ID4")
		)
		(pad "DH5" smd circle
			(at -31.170118 35.999928 180)
			(size 0.450088 0.450088)
			(layers "F.Cu" "F.Mask" "F.Paste")
			(net "GND")
		)
		(pad "DH6" smd circle
			(at -30.230064 35.999928 180)
			(size 0.450088 0.450088)
			(layers "F.Cu" "F.Mask" "F.Paste")
			(net "RST_CPU0_SYS_N")
		)
		(pad "DH7" smd circle
			(at -29.29001 35.999928 180)
			(size 0.450088 0.450088)
			(layers "F.Cu" "F.Mask" "F.Paste")
			(net "CPU0_PWR_BTN_N")
		)
		(pad "DH8" smd circle
			(at -28.349956 35.999928 180)
			(size 0.450088 0.450088)
			(layers "F.Cu" "F.Mask" "F.Paste")
			(net "CPU0_RTC_LDO_SELECT")
		)
		(pad "DH9" smd circle
			(at -27.409902 35.999928 180)
			(size 0.450088 0.450088)
			(layers "F.Cu" "F.Mask" "F.Paste")
			(net "CLK_CPU0_RTCCLK")
		)
		(pad "DH10" smd circle
			(at -26.470102 35.999928 180)
			(size 0.450088 0.450088)
			(layers "F.Cu" "F.Mask" "F.Paste")
			(net "CPU0_SP5R4")
		)
		(pad "DH11" smd circle
			(at -25.530048 35.999928 180)
			(size 0.450088 0.450088)
			(layers "F.Cu" "F.Mask" "F.Paste")
			(net "GND")
		)
		(pad "DH12" smd circle
			(at -24.589994 35.999928 180)
			(size 0.450088 0.450088)
			(layers "F.Cu" "F.Mask" "F.Paste")
			(net "SMB_CPU0_4_R_SDA")
		)
		(pad "DH13" smd circle
			(at -23.64994 35.999928 180)
			(size 0.450088 0.450088)
			(layers "F.Cu" "F.Mask" "F.Paste")
			(net "Net_1947")
		)
		(pad "DH14" smd circle
			(at -22.709886 35.999928 180)
			(size 0.450088 0.450088)
			(layers "F.Cu" "F.Mask" "F.Paste")
			(net "Net_1951")
		)
		(pad "DH15" smd circle
			(at -21.770086 35.999928 180)
			(size 0.450088 0.450088)
			(layers "F.Cu" "F.Mask" "F.Paste")
			(net "IRQ_TPM_SPI_R_N")
		)
		(pad "DH16" smd circle
			(at -20.830032 35.999928 180)
			(size 0.450088 0.450088)
			(layers "F.Cu" "F.Mask" "F.Paste")
			(net "IRQ_SMI_ACTIVE_N")
		)
		(pad "DH17" smd circle
			(at -19.889978 35.999928 180)
			(size 0.450088 0.450088)
			(layers "F.Cu" "F.Mask" "F.Paste")
			(net "Net_1941")
		)
		(pad "DH18" smd circle
			(at -18.949924 35.999928 180)
			(size 0.450088 0.450088)
			(layers "F.Cu" "F.Mask" "F.Paste")
			(net "GND")
		)
		(pad "DH19" smd circle
			(at -18.010124 35.999928 180)
			(size 0.450088 0.450088)
			(layers "F.Cu" "F.Mask" "F.Paste")
			(net "PVDDCR_CPU1_P0")
		)
		(pad "DH20" smd circle
			(at -17.07007 35.999928 180)
			(size 0.450088 0.450088)
			(layers "F.Cu" "F.Mask" "F.Paste")
			(net "PVDDCR_CPU1_P0")
		)
		(pad "DH21" smd circle
			(at -16.130016 35.999928 180)
			(size 0.450088 0.450088)
			(layers "F.Cu" "F.Mask" "F.Paste")
			(net "Net_1942")
		)
		(pad "DH22" smd circle
			(at -15.189962 35.999928 180)
			(size 0.450088 0.450088)
			(layers "F.Cu" "F.Mask" "F.Paste")
			(net "PVDDCR_CPU1_P0")
		)
		(pad "DH23" smd circle
			(at -14.249908 35.999928 180)
			(size 0.450088 0.450088)
			(layers "F.Cu" "F.Mask" "F.Paste")
			(net "PVDDCR_CPU1_P0")
		)
		(pad "DH24" smd circle
			(at -13.310108 35.999928 180)
			(size 0.450088 0.450088)
			(layers "F.Cu" "F.Mask" "F.Paste")
			(net "ESPI_CPU0_R_D0")
		)
		(pad "DH25" smd circle
			(at -12.370054 35.999928 180)
			(size 0.450088 0.450088)
			(layers "F.Cu" "F.Mask" "F.Paste")
			(net "PVDDCR_CPU1_P0")
		)
		(pad "DH26" smd circle
			(at -11.43 35.999928 180)
			(size 0.450088 0.450088)
			(layers "F.Cu" "F.Mask" "F.Paste")
			(net "PVDDCR_CPU1_P0")
		)
		(pad "DH27" smd circle
			(at -10.489946 35.999928 180)
			(size 0.450088 0.450088)
			(layers "F.Cu" "F.Mask" "F.Paste")
			(net "NC_CPU0_SPI_CS2_N")
		)
		(pad "DH28" smd circle
			(at -9.549892 35.999928 180)
			(size 0.450088 0.450088)
			(layers "F.Cu" "F.Mask" "F.Paste")
			(net "PVDDCR_CPU1_P0")
		)
		(pad "DH29" smd circle
			(at -8.610092 35.999928 180)
			(size 0.450088 0.450088)
			(layers "F.Cu" "F.Mask" "F.Paste")
			(net "PVDDCR_CPU1_P0")
		)
		(pad "DH30" smd circle
			(at -7.670038 35.999928 180)
			(size 0.450088 0.450088)
			(layers "F.Cu" "F.Mask" "F.Paste")
			(net "BOOT_RDY_R_H")
		)
		(pad "DH31" smd circle
			(at -6.729984 35.999928 180)
			(size 0.450088 0.450088)
			(layers "F.Cu" "F.Mask" "F.Paste")
			(net "PVDDCR_CPU1_P0")
		)
		(pad "DH32" smd circle
			(at -5.78993 35.999928 180)
			(size 0.450088 0.450088)
			(layers "F.Cu" "F.Mask" "F.Paste")
			(net "PVDDCR_CPU1_P0")
		)
		(pad "DH33" smd circle
			(at -4.849876 35.999928 180)
			(size 0.450088 0.450088)
			(layers "F.Cu" "F.Mask" "F.Paste")
			(net "UART_CPU0_SCM_UART1_RX")
		)
		(pad "DH34" smd circle
			(at -3.910076 35.999928 180)
			(size 0.450088 0.450088)
			(layers "F.Cu" "F.Mask" "F.Paste")
			(net "PVDDCR_CPU1_P0")
		)
		(pad "DH35" smd circle
			(at -2.970022 35.999928 180)
			(size 0.450088 0.450088)
			(layers "F.Cu" "F.Mask" "F.Paste")
			(net "PVDDCR_CPU1_P0")
		)
		(pad "DH36" smd circle
			(at -2.029968 35.999928 180)
			(size 0.450088 0.450088)
			(layers "F.Cu" "F.Mask" "F.Paste")
			(net "CPU0_PWR_GD_OUT")
		)
		(pad "DH37" smd circle
			(at -1.089914 35.999928 180)
			(size 0.450088 0.450088)
			(layers "F.Cu" "F.Mask" "F.Paste")
			(net "GND")
		)
		(pad "DH39" smd circle
			(at 0.78994 35.999928 180)
			(size 0.450088 0.450088)
			(layers "F.Cu" "F.Mask" "F.Paste")
			(net "GND")
		)
		(pad "DH40" smd circle
			(at 1.729994 35.999928 180)
			(size 0.450088 0.450088)
			(layers "F.Cu" "F.Mask" "F.Paste")
			(net "Net_1893")
		)
		(pad "DH41" smd circle
			(at 2.670048 35.999928 180)
			(size 0.450088 0.450088)
			(layers "F.Cu" "F.Mask" "F.Paste")
			(net "PVDDCR_CPU1_P0")
		)
		(pad "DH42" smd circle
			(at 3.610102 35.999928 180)
			(size 0.450088 0.450088)
			(layers "F.Cu" "F.Mask" "F.Paste")
			(net "PVDDCR_CPU1_P0")
		)
		(pad "DH43" smd circle
			(at 4.549902 35.999928 180)
			(size 0.450088 0.450088)
			(layers "F.Cu" "F.Mask" "F.Paste")
			(net "GND")
		)
		(pad "DH44" smd circle
			(at 5.489956 35.999928 180)
			(size 0.450088 0.450088)
			(layers "F.Cu" "F.Mask" "F.Paste")
			(net "PVDDCR_CPU1_P0")
		)
		(pad "DH45" smd circle
			(at 6.43001 35.999928 180)
			(size 0.450088 0.450088)
			(layers "F.Cu" "F.Mask" "F.Paste")
			(net "PVDDCR_CPU1_P0")
		)
		(pad "DH46" smd circle
			(at 7.370064 35.999928 180)
			(size 0.450088 0.450088)
			(layers "F.Cu" "F.Mask" "F.Paste")
			(net "GND")
		)
		(pad "DH47" smd circle
			(at 8.310118 35.999928 180)
			(size 0.450088 0.450088)
			(layers "F.Cu" "F.Mask" "F.Paste")
			(net "PVDDCR_CPU1_P0")
		)
		(pad "DH48" smd circle
			(at 9.249918 35.999928 180)
			(size 0.450088 0.450088)
			(layers "F.Cu" "F.Mask" "F.Paste")
			(net "PVDDCR_CPU1_P0")
		)
		(pad "DH49" smd circle
			(at 10.189972 35.999928 180)
			(size 0.450088 0.450088)
			(layers "F.Cu" "F.Mask" "F.Paste")
			(net "GND")
		)
		(pad "DH50" smd circle
			(at 11.130026 35.999928 180)
			(size 0.450088 0.450088)
			(layers "F.Cu" "F.Mask" "F.Paste")
			(net "PVDDCR_CPU1_P0")
		)
		(pad "DH51" smd circle
			(at 12.07008 35.999928 180)
			(size 0.450088 0.450088)
			(layers "F.Cu" "F.Mask" "F.Paste")
			(net "PVDDCR_CPU1_P0")
		)
		(pad "DH52" smd circle
			(at 13.00988 35.999928 180)
			(size 0.450088 0.450088)
			(layers "F.Cu" "F.Mask" "F.Paste")
			(net "GND")
		)
		(pad "DH53" smd circle
			(at 13.949934 35.999928 180)
			(size 0.450088 0.450088)
			(layers "F.Cu" "F.Mask" "F.Paste")
			(net "PVDDCR_CPU1_P0")
		)
		(pad "DH54" smd circle
			(at 14.889988 35.999928 180)
			(size 0.450088 0.450088)
			(layers "F.Cu" "F.Mask" "F.Paste")
			(net "PVDDCR_CPU1_P0")
		)
		(pad "DH55" smd circle
			(at 15.830042 35.999928 180)
			(size 0.450088 0.450088)
			(layers "F.Cu" "F.Mask" "F.Paste")
			(net "GND")
		)
		(pad "DH56" smd circle
			(at 16.770096 35.999928 180)
			(size 0.450088 0.450088)
			(layers "F.Cu" "F.Mask" "F.Paste")
			(net "PVDDCR_CPU1_P0")
		)
		(pad "DH57" smd circle
			(at 17.709896 35.999928 180)
			(size 0.450088 0.450088)
			(layers "F.Cu" "F.Mask" "F.Paste")
			(net "PVDDCR_CPU1_P0")
		)
		(pad "DH58" smd circle
			(at 18.64995 35.999928 180)
			(size 0.450088 0.450088)
			(layers "F.Cu" "F.Mask" "F.Paste")
			(net "Net_1896")
		)
		(pad "DH59" smd circle
			(at 19.590004 35.999928 180)
			(size 0.450088 0.450088)
			(layers "F.Cu" "F.Mask" "F.Paste")
			(net "GND")
		)
		(pad "DH60" smd circle
			(at 20.530058 35.999928 180)
			(size 0.450088 0.450088)
			(layers "F.Cu" "F.Mask" "F.Paste")
			(net "USB2_CPU0_P11_DP")
		)
		(pad "DH61" smd circle
			(at 21.470112 35.999928 180)
			(size 0.450088 0.450088)
			(layers "F.Cu" "F.Mask" "F.Paste")
			(net "GND")
		)
		(pad "DH62" smd circle
			(at 22.409912 35.999928 180)
			(size 0.450088 0.450088)
			(layers "F.Cu" "F.Mask" "F.Paste")
			(net "Net_1894")
		)
		(pad "DH63" smd circle
			(at 23.349966 35.999928 180)
			(size 0.450088 0.450088)
			(layers "F.Cu" "F.Mask" "F.Paste")
			(net "GND")
		)
		(pad "DH64" smd circle
			(at 24.29002 35.999928 180)
			(size 0.450088 0.450088)
			(layers "F.Cu" "F.Mask" "F.Paste")
			(net "GND")
		)
		(pad "DH65" smd circle
			(at 25.230074 35.999928 180)
			(size 0.450088 0.450088)
			(layers "F.Cu" "F.Mask" "F.Paste")
			(net "Net_1889")
		)
		(pad "DH66" smd circle
			(at 26.170128 35.999928 180)
			(size 0.450088 0.450088)
			(layers "F.Cu" "F.Mask" "F.Paste")
			(net "GND")
		)
		(pad "DH67" smd circle
			(at 27.109928 35.999928 180)
			(size 0.450088 0.450088)
			(layers "F.Cu" "F.Mask" "F.Paste")
			(net "USB2_CPU0_P10_DN")
		)
		(pad "DH68" smd circle
			(at 28.049982 35.999928 180)
			(size 0.450088 0.450088)
			(layers "F.Cu" "F.Mask" "F.Paste")
			(net "GND")
		)
		(pad "DH69" smd circle
			(at 28.990036 35.999928 180)
			(size 0.450088 0.450088)
			(layers "F.Cu" "F.Mask" "F.Paste")
			(net "Net_1892")
		)
		(pad "DH70" smd circle
			(at 29.93009 35.999928 180)
			(size 0.450088 0.450088)
			(layers "F.Cu" "F.Mask" "F.Paste")
			(net "GND")
		)
		(pad "DH71" smd circle
			(at 30.86989 35.999928 180)
			(size 0.450088 0.450088)
			(layers "F.Cu" "F.Mask" "F.Paste")
			(net "SMB_APML_CPU0_SDA")
		)
		(pad "DH72" smd circle
			(at 31.809944 35.999928 180)
			(size 0.450088 0.450088)
			(layers "F.Cu" "F.Mask" "F.Paste")
			(net "SVID_PVDDCR_CPU1_P0_SVD")
		)
		(pad "DH73" smd circle
			(at 32.749998 35.999928 180)
			(size 0.450088 0.450088)
			(layers "F.Cu" "F.Mask" "F.Paste")
			(net "CPU0_SP5R3")
		)
		(pad "DJ3" smd circle
			(at -32.580072 36.809934 180)
			(size 0.450088 0.450088)
			(layers "F.Cu" "F.Mask" "F.Paste")
			(net "VSENSE_VSS_SENSE_C_P0")
		)
		(pad "DJ4" smd circle
			(at -31.640018 36.809934 180)
			(size 0.450088 0.450088)
			(layers "F.Cu" "F.Mask" "F.Paste")
			(net "Net_1943")
		)
	)
)
